(kicad_pcb
	(version 20260206)
	(generator "pcbnew")
	(generator_version "10.0")
	(general
		(thickness 1.6)
		(legacy_teardrops no)
	)
	(paper "A4")
	(title_block
		(title "Bryce Canyon_IOM_IOC_16318-2_OCP.brd")
		(comment 1 "Bryce Canyon / footprints 1577-1584 of 1605")
	)
	(layers
		(0 "F.Cu" signal "TOP")
		(4 "In1.Cu" signal "L2GND")
		(6 "In2.Cu" signal "L3")
		(8 "In3.Cu" signal "L4VCC")
		(10 "In4.Cu" signal "L5VCC")
		(12 "In5.Cu" signal "L6")
		(14 "In6.Cu" signal "L7GND")
		(2 "B.Cu" signal "BOTTOM")
		(9 "F.Adhes" user "F.Adhesive")
		(11 "B.Adhes" user "B.Adhesive")
		(13 "F.Paste" user "Package Geometry/Pastemask Top")
		(15 "B.Paste" user "Package Geometry/Pastemask Bottom")
		(5 "F.SilkS" user "Ref Des/Silkscreen Top")
		(7 "B.SilkS" user "Ref Des/Silkscreen Bottom")
		(1 "F.Mask" user "Board Geometry/Soldermask Top")
		(3 "B.Mask" user "Board Geometry/Soldermask Bottom")
		(17 "Dwgs.User" user "User.Drawings")
		(19 "Cmts.User" user "User.Comments")
		(21 "Eco1.User" user "User.Eco1")
		(23 "Eco2.User" user "User.Eco2")
		(25 "Edge.Cuts" user "Board Geometry/Outline")
		(27 "Margin" user)
		(31 "F.CrtYd" user "Package Geometry/Place Bound Top")
		(29 "B.CrtYd" user "Package Geometry/Place Bound Bottom")
		(35 "F.Fab" user "Ref Des/Assembly Top")
		(33 "B.Fab" user "Ref Des/Assembly Bottom")
	)
	(footprint ""
		(layer "B.Cu")
		(at 39.544752 -132.622036 -90)
		(property "Reference" "R612"
			(at 0 0 90)
			(layer "B.SilkS")
			(hide yes)
			(effects
				(font
					(size 1.27 1.27)
				)
				(justify mirror)
			)
		)
		(property "Value" "4K7R2F-GP"
			(at -0.064008 -3.993896 270)
			(unlocked yes)
			(layer "B.Fab")
			(hide yes)
			(effects
				(font
					(size 1.016 1.016)
					(thickness 0.1524)
				)
				(justify mirror)
			)
		)
		(property "Device Type" "R402H16"
			(at -0.064008 -5.517896 270)
			(unlocked yes)
			(layer "B.Fab")
			(hide yes)
			(effects
				(font
					(size 1.016 1.016)
					(thickness 0.1524)
				)
				(justify mirror)
			)
		)
		(duplicate_pad_numbers_are_jumpers no)
		(fp_line
			(start -0.508 -0.9398)
			(end 0.508 -0.9398)
			(stroke
				(width 0.1524)
				(type default)
			)
			(layer "B.SilkS")
		)
		(fp_line
			(start 0.508 -0.9398)
			(end 0.508 0.9398)
			(stroke
				(width 0.1524)
				(type default)
			)
			(layer "B.SilkS")
		)
		(fp_rect
			(start 0.508 0.9398)
			(end -0.508 -0.9398)
			(stroke
				(width 0)
				(type default)
			)
			(fill no)
			(layer "B.CrtYd")
		)
		(fp_rect
			(start 0.508 0.9398)
			(end -0.508 -0.9398)
			(stroke
				(width 0)
				(type default)
			)
			(fill no)
			(layer "B.Fab")
		)
		(pad "1" smd custom
			(at 0 -0.4445 90)
			(size 0.1397 0.1397)
			(layers "B.Cu" "B.Mask" "B.Paste")
			(net "P3V3_STBY")
			(options
				(clearance outline)
				(anchor circle)
			)
			(primitives
				(gr_poly
					(pts
						(arc
							(start -0.1778 0.2794)
							(mid -0.249642 0.249642)
							(end -0.2794 0.1778)
						)
						(arc
							(start -0.2794 -0.1778)
							(mid -0.249642 -0.249642)
							(end -0.1778 -0.2794)
						)
						(arc
							(start 0.1778 -0.2794)
							(mid 0.249642 -0.249642)
							(end 0.2794 -0.1778)
						)
						(arc
							(start 0.2794 0.1778)
							(mid 0.249642 0.249642)
							(end 0.1778 0.2794)
						)
					)
					(width 0)
					(fill yes)
				)
			)
		)
		(pad "2" smd custom
			(at 0 0.4445 90)
			(size 0.1397 0.1397)
			(layers "B.Cu" "B.Mask" "B.Paste")
			(net "BMC_ML_PWR_BLUE_LED")
			(options
				(clearance outline)
				(anchor circle)
			)
			(primitives
				(gr_poly
					(pts
						(arc
							(start -0.1778 0.2794)
							(mid -0.249642 0.249642)
							(end -0.2794 0.1778)
						)
						(arc
							(start -0.2794 -0.1778)
							(mid -0.249642 -0.249642)
							(end -0.1778 -0.2794)
						)
						(arc
							(start 0.1778 -0.2794)
							(mid 0.249642 -0.249642)
							(end 0.2794 -0.1778)
						)
						(arc
							(start 0.2794 0.1778)
							(mid 0.249642 0.249642)
							(end 0.1778 0.2794)
						)
					)
					(width 0)
					(fill yes)
				)
			)
		)
	)
	(footprint ""
		(layer "B.Cu")
		(at 10.1854 -142.4686 90)
		(property "Reference" "R211"
			(at 0 0 90)
			(layer "B.SilkS")
			(hide yes)
			(effects
				(font
					(size 1.27 1.27)
				)
				(justify mirror)
			)
		)
		(property "Value" "120R2F-GP"
			(at -0.064008 -3.993896 90)
			(unlocked yes)
			(layer "B.Fab")
			(hide yes)
			(effects
				(font
					(size 1.016 1.016)
					(thickness 0.1524)
				)
				(justify mirror)
			)
		)
		(property "Device Type" "R402H16"
			(at -0.064008 -5.517896 90)
			(unlocked yes)
			(layer "B.Fab")
			(hide yes)
			(effects
				(font
					(size 1.016 1.016)
					(thickness 0.1524)
				)
				(justify mirror)
			)
		)
		(duplicate_pad_numbers_are_jumpers no)
		(fp_line
			(start 0.508 -0.9398)
			(end 0.508 0.9398)
			(stroke
				(width 0.1524)
				(type default)
			)
			(layer "B.SilkS")
		)
		(fp_line
			(start -0.508 -0.9398)
			(end 0.508 -0.9398)
			(stroke
				(width 0.1524)
				(type default)
			)
			(layer "B.SilkS")
		)
		(fp_rect
			(start 0.508 0.9398)
			(end -0.508 -0.9398)
			(stroke
				(width 0)
				(type default)
			)
			(fill no)
			(layer "B.CrtYd")
		)
		(fp_rect
			(start 0.508 0.9398)
			(end -0.508 -0.9398)
			(stroke
				(width 0)
				(type default)
			)
			(fill no)
			(layer "B.Fab")
		)
		(pad "1" smd custom
			(at 0 -0.4445 270)
			(size 0.1397 0.1397)
			(layers "B.Cu" "B.Mask" "B.Paste")
			(net "GND")
			(options
				(clearance outline)
				(anchor circle)
			)
			(primitives
				(gr_poly
					(pts
						(arc
							(start -0.1778 0.2794)
							(mid -0.249642 0.249642)
							(end -0.2794 0.1778)
						)
						(arc
							(start -0.2794 -0.1778)
							(mid -0.249642 -0.249642)
							(end -0.1778 -0.2794)
						)
						(arc
							(start 0.1778 -0.2794)
							(mid 0.249642 -0.249642)
							(end 0.2794 -0.1778)
						)
						(arc
							(start 0.2794 0.1778)
							(mid 0.249642 0.249642)
							(end 0.1778 0.2794)
						)
					)
					(width 0)
					(fill yes)
				)
			)
		)
		(pad "2" smd custom
			(at 0 0.4445 270)
			(size 0.1397 0.1397)
			(layers "B.Cu" "B.Mask" "B.Paste")
			(net "MEMODT")
			(options
				(clearance outline)
				(anchor circle)
			)
			(primitives
				(gr_poly
					(pts
						(arc
							(start -0.1778 0.2794)
							(mid -0.249642 0.249642)
							(end -0.2794 0.1778)
						)
						(arc
							(start -0.2794 -0.1778)
							(mid -0.249642 -0.249642)
							(end -0.1778 -0.2794)
						)
						(arc
							(start 0.1778 -0.2794)
							(mid 0.249642 -0.249642)
							(end 0.2794 -0.1778)
						)
						(arc
							(start 0.2794 0.1778)
							(mid 0.249642 0.249642)
							(end 0.1778 0.2794)
						)
					)
					(width 0)
					(fill yes)
				)
			)
		)
	)
	(footprint ""
		(layer "B.Cu")
		(at 17.723612 -131.007358 180)
		(property "Reference" "R241"
			(at 0 0 0)
			(layer "B.SilkS")
			(hide yes)
			(effects
				(font
					(size 1.27 1.27)
				)
				(justify mirror)
			)
		)
		(property "Value" "120R2F-GP"
			(at -0.064008 -3.993896 180)
			(unlocked yes)
			(layer "B.Fab")
			(hide yes)
			(effects
				(font
					(size 1.016 1.016)
					(thickness 0.1524)
				)
				(justify mirror)
			)
		)
		(property "Device Type" "R402H16"
			(at -0.064008 -5.517896 180)
			(unlocked yes)
			(layer "B.Fab")
			(hide yes)
			(effects
				(font
					(size 1.016 1.016)
					(thickness 0.1524)
				)
				(justify mirror)
			)
		)
		(duplicate_pad_numbers_are_jumpers no)
		(fp_line
			(start 0.508 -0.9398)
			(end 0.508 0.9398)
			(stroke
				(width 0.1524)
				(type default)
			)
			(layer "B.SilkS")
		)
		(fp_line
			(start -0.508 -0.9398)
			(end 0.508 -0.9398)
			(stroke
				(width 0.1524)
				(type default)
			)
			(layer "B.SilkS")
		)
		(fp_rect
			(start 0.508 0.9398)
			(end -0.508 -0.9398)
			(stroke
				(width 0)
				(type default)
			)
			(fill no)
			(layer "B.CrtYd")
		)
		(fp_rect
			(start 0.508 0.9398)
			(end -0.508 -0.9398)
			(stroke
				(width 0)
				(type default)
			)
			(fill no)
			(layer "B.Fab")
		)
		(pad "1" smd custom
			(at 0 -0.4445)
			(size 0.1397 0.1397)
			(layers "B.Cu" "B.Mask" "B.Paste")
			(net "MEMA_3")
			(options
				(clearance outline)
				(anchor circle)
			)
			(primitives
				(gr_poly
					(pts
						(arc
							(start -0.1778 0.2794)
							(mid -0.249642 0.249642)
							(end -0.2794 0.1778)
						)
						(arc
							(start -0.2794 -0.1778)
							(mid -0.249642 -0.249642)
							(end -0.1778 -0.2794)
						)
						(arc
							(start 0.1778 -0.2794)
							(mid 0.249642 -0.249642)
							(end 0.2794 -0.1778)
						)
						(arc
							(start 0.2794 0.1778)
							(mid 0.249642 0.249642)
							(end 0.1778 0.2794)
						)
					)
					(width 0)
					(fill yes)
				)
			)
		)
		(pad "2" smd custom
			(at 0 0.4445)
			(size 0.1397 0.1397)
			(layers "B.Cu" "B.Mask" "B.Paste")
			(net "P1V2_STBY")
			(options
				(clearance outline)
				(anchor circle)
			)
			(primitives
				(gr_poly
					(pts
						(arc
							(start -0.1778 0.2794)
							(mid -0.249642 0.249642)
							(end -0.2794 0.1778)
						)
						(arc
							(start -0.2794 -0.1778)
							(mid -0.249642 -0.249642)
							(end -0.1778 -0.2794)
						)
						(arc
							(start 0.1778 -0.2794)
							(mid 0.249642 -0.249642)
							(end 0.2794 -0.1778)
						)
						(arc
							(start 0.2794 0.1778)
							(mid 0.249642 0.249642)
							(end 0.1778 0.2794)
						)
					)
					(width 0)
					(fill yes)
				)
			)
		)
	)
	(footprint ""
		(layer "B.Cu")
		(at 82.504788 -46.810676 -90)
		(property "Reference" "C511"
			(at 0 0 90)
			(layer "B.SilkS")
			(hide yes)
			(effects
				(font
					(size 1.27 1.27)
				)
				(justify mirror)
			)
		)
		(property "Value" "SC10U16V5KX-7-GP-U"
			(at 0.0762 -6.1214 270)
			(unlocked yes)
			(layer "B.Fab")
			(hide yes)
			(effects
				(font
					(size 1.016 1.016)
					(thickness 0.1524)
				)
				(justify mirror)
			)
		)
		(property "Device Type" "C805H58"
			(at 0.0762 -8.1534 270)
			(unlocked yes)
			(layer "B.Fab")
			(hide yes)
			(effects
				(font
					(size 1.016 1.016)
					(thickness 0.1524)
				)
				(justify mirror)
			)
		)
		(duplicate_pad_numbers_are_jumpers no)
		(fp_line
			(start -0.635 0)
			(end 0.635 0)
			(stroke
				(width 0.508)
				(type default)
			)
			(layer "B.SilkS")
		)
		(fp_rect
			(start 0.9652 1.778)
			(end -0.9652 -1.778)
			(stroke
				(width 0)
				(type default)
			)
			(fill no)
			(layer "B.CrtYd")
		)
		(fp_poly
			(pts
				(xy 0.9652 -1.778) (xy -0.9652 -1.778) (xy -0.9652 1.778) (xy 0.9652 1.778)
			)
			(stroke
				(width 0)
				(type default)
			)
			(fill no)
			(layer "B.Fab")
		)
		(pad "1" smd rect
			(at 0 -0.9652 90)
			(size 1.397 1.143)
			(layers "B.Cu" "B.Mask" "B.Paste")
			(net "P5V_STBY")
		)
		(pad "2" smd rect
			(at 0 0.9652 90)
			(size 1.397 1.143)
			(layers "B.Cu" "B.Mask" "B.Paste")
			(net "GND")
		)
	)
	(footprint ""
		(layer "B.Cu")
		(at 209.033872 -59.934856 -90)
		(property "Reference" "R594"
			(at 0 0 90)
			(layer "B.SilkS")
			(hide yes)
			(effects
				(font
					(size 1.27 1.27)
				)
				(justify mirror)
			)
		)
		(property "Value" "2K2R2F-GP"
			(at -0.064008 -3.993896 270)
			(unlocked yes)
			(layer "B.Fab")
			(hide yes)
			(effects
				(font
					(size 1.016 1.016)
					(thickness 0.1524)
				)
				(justify mirror)
			)
		)
		(property "Device Type" "R402H16"
			(at -0.064008 -5.517896 270)
			(unlocked yes)
			(layer "B.Fab")
			(hide yes)
			(effects
				(font
					(size 1.016 1.016)
					(thickness 0.1524)
				)
				(justify mirror)
			)
		)
		(duplicate_pad_numbers_are_jumpers no)
		(fp_line
			(start -0.508 -0.9398)
			(end 0.508 -0.9398)
			(stroke
				(width 0.1524)
				(type default)
			)
			(layer "B.SilkS")
		)
		(fp_line
			(start 0.508 -0.9398)
			(end 0.508 0.9398)
			(stroke
				(width 0.1524)
				(type default)
			)
			(layer "B.SilkS")
		)
		(fp_rect
			(start 0.508 0.9398)
			(end -0.508 -0.9398)
			(stroke
				(width 0)
				(type default)
			)
			(fill no)
			(layer "B.CrtYd")
		)
		(fp_rect
			(start 0.508 0.9398)
			(end -0.508 -0.9398)
			(stroke
				(width 0)
				(type default)
			)
			(fill no)
			(layer "B.Fab")
		)
		(pad "1" smd custom
			(at 0 -0.4445 90)
			(size 0.1397 0.1397)
			(layers "B.Cu" "B.Mask" "B.Paste")
			(net "P1V8")
			(options
				(clearance outline)
				(anchor circle)
			)
			(primitives
				(gr_poly
					(pts
						(arc
							(start -0.1778 0.2794)
							(mid -0.249642 0.249642)
							(end -0.2794 0.1778)
						)
						(arc
							(start -0.2794 -0.1778)
							(mid -0.249642 -0.249642)
							(end -0.1778 -0.2794)
						)
						(arc
							(start 0.1778 -0.2794)
							(mid 0.249642 -0.249642)
							(end 0.2794 -0.1778)
						)
						(arc
							(start 0.2794 0.1778)
							(mid 0.249642 0.249642)
							(end 0.1778 0.2794)
						)
					)
					(width 0)
					(fill yes)
				)
			)
		)
		(pad "2" smd custom
			(at 0 0.4445 90)
			(size 0.1397 0.1397)
			(layers "B.Cu" "B.Mask" "B.Paste")
			(net "SIO_DOUT_1")
			(options
				(clearance outline)
				(anchor circle)
			)
			(primitives
				(gr_poly
					(pts
						(arc
							(start -0.1778 0.2794)
							(mid -0.249642 0.249642)
							(end -0.2794 0.1778)
						)
						(arc
							(start -0.2794 -0.1778)
							(mid -0.249642 -0.249642)
							(end -0.1778 -0.2794)
						)
						(arc
							(start 0.1778 -0.2794)
							(mid 0.249642 -0.249642)
							(end 0.2794 -0.1778)
						)
						(arc
							(start 0.2794 0.1778)
							(mid 0.249642 0.249642)
							(end 0.1778 0.2794)
						)
					)
					(width 0)
					(fill yes)
				)
			)
		)
	)
	(footprint ""
		(layer "B.Cu")
		(at 197.25386 -62.96152 90)
		(property "Reference" "C391"
			(at 0 0 90)
			(layer "B.SilkS")
			(hide yes)
			(effects
				(font
					(size 1.27 1.27)
				)
				(justify mirror)
			)
		)
		(property "Value" "SC1U16V2KX-7-GP"
			(at -1.7526 -1.6002 90)
			(unlocked yes)
			(layer "B.Fab")
			(hide yes)
			(effects
				(font
					(size 1.016 1.016)
					(thickness 0.1524)
				)
				(justify mirror)
			)
		)
		(property "Device Type" "C402-TO0D2H24"
			(at -1.7526 -3.1242 90)
			(unlocked yes)
			(layer "B.Fab")
			(hide yes)
			(effects
				(font
					(size 1.016 1.016)
					(thickness 0.1524)
				)
				(justify mirror)
			)
		)
		(duplicate_pad_numbers_are_jumpers no)
		(fp_rect
			(start 0.4826 0.889)
			(end -0.4826 -0.889)
			(stroke
				(width 0)
				(type default)
			)
			(fill no)
			(layer "B.CrtYd")
		)
		(fp_rect
			(start 0.4826 0.889)
			(end -0.4826 -0.889)
			(stroke
				(width 0)
				(type default)
			)
			(fill no)
			(layer "B.Fab")
		)
		(pad "1" smd custom
			(at 0 -0.4572 270)
			(size 0.1524 0.1524)
			(layers "B.Cu" "B.Mask" "B.Paste")
			(net "P0V975")
			(options
				(clearance outline)
				(anchor circle)
			)
			(primitives
				(gr_poly
					(pts
						(arc
							(start -0.254 -0.3048)
							(mid -0.325842 -0.275042)
							(end -0.3556 -0.2032)
						)
						(arc
							(start -0.3556 0.2032)
							(mid -0.325842 0.275042)
							(end -0.254 0.3048)
						)
						(arc
							(start 0.254 0.3048)
							(mid 0.325842 0.275042)
							(end 0.3556 0.2032)
						)
						(arc
							(start 0.3556 -0.2032)
							(mid 0.325842 -0.275042)
							(end 0.254 -0.3048)
						)
					)
					(width 0)
					(fill yes)
				)
			)
		)
		(pad "2" smd custom
			(at 0 0.4572 270)
			(size 0.1524 0.1524)
			(layers "B.Cu" "B.Mask" "B.Paste")
			(net "GND")
			(options
				(clearance outline)
				(anchor circle)
			)
			(primitives
				(gr_poly
					(pts
						(arc
							(start -0.254 -0.3048)
							(mid -0.325842 -0.275042)
							(end -0.3556 -0.2032)
						)
						(arc
							(start -0.3556 0.2032)
							(mid -0.325842 0.275042)
							(end -0.254 0.3048)
						)
						(arc
							(start 0.254 0.3048)
							(mid 0.325842 0.275042)
							(end 0.3556 0.2032)
						)
						(arc
							(start 0.3556 -0.2032)
							(mid 0.325842 -0.275042)
							(end 0.254 -0.3048)
						)
					)
					(width 0)
					(fill yes)
				)
			)
		)
	)
	(footprint ""
		(layer "B.Cu")
		(at 45.466 -128.2192)
		(property "Reference" "R292"
			(at 0 0 0)
			(layer "B.SilkS")
			(hide yes)
			(effects
				(font
					(size 1.27 1.27)
				)
				(justify mirror)
			)
		)
		(property "Value" "0R2J-2-GP"
			(at -0.064008 -3.993896 0)
			(unlocked yes)
			(layer "B.Fab")
			(hide yes)
			(effects
				(font
					(size 1.016 1.016)
					(thickness 0.1524)
				)
				(justify mirror)
			)
		)
		(property "Device Type" "R402H16"
			(at -0.064008 -5.517896 0)
			(unlocked yes)
			(layer "B.Fab")
			(hide yes)
			(effects
				(font
					(size 1.016 1.016)
					(thickness 0.1524)
				)
				(justify mirror)
			)
		)
		(duplicate_pad_numbers_are_jumpers no)
		(fp_line
			(start -0.508 -0.9398)
			(end 0.508 -0.9398)
			(stroke
				(width 0.1524)
				(type default)
			)
			(layer "B.SilkS")
		)
		(fp_line
			(start 0.508 -0.9398)
			(end 0.508 0.9398)
			(stroke
				(width 0.1524)
				(type default)
			)
			(layer "B.SilkS")
		)
		(fp_rect
			(start 0.508 0.9398)
			(end -0.508 -0.9398)
			(stroke
				(width 0)
				(type default)
			)
			(fill no)
			(layer "B.CrtYd")
		)
		(fp_rect
			(start 0.508 0.9398)
			(end -0.508 -0.9398)
			(stroke
				(width 0)
				(type default)
			)
			(fill no)
			(layer "B.Fab")
		)
		(pad "1" smd custom
			(at 0 -0.4445 180)
			(size 0.1397 0.1397)
			(layers "B.Cu" "B.Mask" "B.Paste")
			(net "IOM_LOC_INS_N")
			(options
				(clearance outline)
				(anchor circle)
			)
			(primitives
				(gr_poly
					(pts
						(arc
							(start -0.1778 0.2794)
							(mid -0.249642 0.249642)
							(end -0.2794 0.1778)
						)
						(arc
							(start -0.2794 -0.1778)
							(mid -0.249642 -0.249642)
							(end -0.1778 -0.2794)
						)
						(arc
							(start 0.1778 -0.2794)
							(mid 0.249642 -0.249642)
							(end 0.2794 -0.1778)
						)
						(arc
							(start 0.2794 0.1778)
							(mid 0.249642 0.249642)
							(end 0.1778 0.2794)
						)
					)
					(width 0)
					(fill yes)
				)
			)
		)
		(pad "2" smd custom
			(at 0 0.4445 180)
			(size 0.1397 0.1397)
			(layers "B.Cu" "B.Mask" "B.Paste")
			(net "GND")
			(options
				(clearance outline)
				(anchor circle)
			)
			(primitives
				(gr_poly
					(pts
						(arc
							(start -0.1778 0.2794)
							(mid -0.249642 0.249642)
							(end -0.2794 0.1778)
						)
						(arc
							(start -0.2794 -0.1778)
							(mid -0.249642 -0.249642)
							(end -0.1778 -0.2794)
						)
						(arc
							(start 0.1778 -0.2794)
							(mid 0.249642 -0.249642)
							(end 0.2794 -0.1778)
						)
						(arc
							(start 0.2794 0.1778)
							(mid 0.249642 0.249642)
							(end 0.1778 0.2794)
						)
					)
					(width 0)
					(fill yes)
				)
			)
		)
	)
	(footprint ""
		(layer "B.Cu")
		(at 90.5764 -132.7404)
		(property "Reference" "C503"
			(at 0 0 0)
			(layer "B.SilkS")
			(hide yes)
			(effects
				(font
					(size 1.27 1.27)
				)
				(justify mirror)
			)
		)
		(property "Value" "SCD1U16V2KX-3GP"
			(at -1.1811 -2.7051 0)
			(unlocked yes)
			(layer "B.Fab")
			(hide yes)
			(effects
				(font
					(size 1.016 1.016)
					(thickness 0.1524)
				)
				(justify mirror)
			)
		)
		(property "Device Type" "C402H22"
			(at -1.1811 -4.2291 0)
			(unlocked yes)
			(layer "B.Fab")
			(hide yes)
			(effects
				(font
					(size 1.016 1.016)
					(thickness 0.1524)
				)
				(justify mirror)
			)
		)
		(duplicate_pad_numbers_are_jumpers no)
		(fp_rect
			(start 0.4318 0.9525)
			(end -0.4318 -0.9525)
			(stroke
				(width 0)
				(type default)
			)
			(fill no)
			(layer "B.CrtYd")
		)
		(fp_rect
			(start 0.4318 0.9525)
			(end -0.4318 -0.9525)
			(stroke
				(width 0)
				(type default)
			)
			(fill no)
			(layer "B.Fab")
		)
		(pad "1" smd custom
			(at 0 -0.4445 180)
			(size 0.1524 0.1524)
			(layers "B.Cu" "B.Mask" "B.Paste")
			(net "P3V3_STBY")
			(options
				(clearance outline)
				(anchor circle)
			)
			(primitives
				(gr_poly
					(pts
						(arc
							(start 0.3048 0.2032)
							(mid 0.275042 0.275042)
							(end 0.2032 0.3048)
						)
						(arc
							(start -0.2032 0.3048)
							(mid -0.275042 0.275042)
							(end -0.3048 0.2032)
						)
						(arc
							(start -0.3048 -0.2032)
							(mid -0.275042 -0.275042)
							(end -0.2032 -0.3048)
						)
						(arc
							(start 0.2032 -0.3048)
							(mid 0.275042 -0.275042)
							(end 0.3048 -0.2032)
						)
					)
					(width 0)
					(fill yes)
				)
			)
		)
		(pad "2" smd custom
			(at 0 0.4445 180)
			(size 0.1524 0.1524)
			(layers "B.Cu" "B.Mask" "B.Paste")
			(net "GND")
			(options
				(clearance outline)
				(anchor circle)
			)
			(primitives
				(gr_poly
					(pts
						(arc
							(start 0.3048 0.2032)
							(mid 0.275042 0.275042)
							(end 0.2032 0.3048)
						)
						(arc
							(start -0.2032 0.3048)
							(mid -0.275042 0.275042)
							(end -0.3048 0.2032)
						)
						(arc
							(start -0.3048 -0.2032)
							(mid -0.275042 -0.275042)
							(end -0.2032 -0.3048)
						)
						(arc
							(start 0.2032 -0.3048)
							(mid 0.275042 -0.275042)
							(end 0.3048 -0.2032)
						)
					)
					(width 0)
					(fill yes)
				)
			)
		)
	)
)
